FILE_TYPE = CONNECTIVITY;
{Allegro Design Entry HDL 16.6-p007 (v16-6-112F) 10/10/2012}
"PAGE_NUMBER" = 243;
0"NC";
1"GND\g";
2"GND\g";
3"PVDDQ_GHJ\g";
4"GND\g";
5"PVDDQ_KLM\g";
6"PVDDQ_GHJ\g";
7"GND\g";
8"PVDDQ_KLM\g";
9"GND\g";
10"PVDDQ_KLM\g";
11"GND\g";
12"PVDDQ_GHJ\g";
%"GND"
"1","(-7100,875)","0","mstr_symbols","I1";
;
HDL_POWER"GND"
BODY_TYPE"PLUMBING"
VOLTAGE"0"
ROOM"VDDQ_ABC_PWR_VR"
BOM_COST"PROC_VRD_VCCIN_CPU0"
SIZE"1B"
CDS_LIB"mstr_symbols";
"A\NAC"1;
%"GND"
"1","(-7125,3125)","0","mstr_symbols","I11";
;
HDL_POWER"GND"
BODY_TYPE"PLUMBING"
VOLTAGE"0"
ROOM"VDDQ_ABC_PWR_VR"
BOM_COST"PROC_VRD_VCCIN_CPU0"
SIZE"1B"
CDS_LIB"mstr_symbols";
"A\NAC"2;
%"CAP"
"1","(-7125,3650)","0","mstr_discrete","I12";
;
CDS_SEC"1"
$SEC"1"
CDS_LOCATION"C5G117"
BOM_COST"MEM_VRD_PVDDQ_CD"
ROOM"VDDQ_KLM_PWR_VR"
CDS_LIB"mstr_discrete"
SIDE_SKU"1S"
VOLTAGE"4V"
TOLERANCE"20%"
PART_NUMBER"602433-112"
PACK_TYPE"0805"
MATERIAL"X5R"
LOCATION"C5G117"
VALUE"100UF";
"A"
$PN"1"3;
"B"
$PN"2"2;
%"CAP"
"1","(-6700,3650)","0","mstr_discrete","I13";
;
CDS_SEC"1"
$SEC"1"
CDS_LOCATION"C5G118"
ROOM"VDDQ_KLM_PWR_VR"
BOM_COST"MEM_VRD_PVDDQ_CD"
CDS_LIB"mstr_discrete"
SIDE_SKU"1S"
LOCATION"C5G118"
VALUE"100UF"
PACK_TYPE"0805"
PART_NUMBER"602433-112"
MATERIAL"X5R"
TOLERANCE"20%"
VOLTAGE"4V";
"A"
$PN"1"3;
"B"
$PN"2"2;
%"PVDDQ_GHJ"
"1","(-7125,4075)","0","mstr_symbols","I26";
;
HDL_POWER"PVDDQ_GHJ"
BODY_TYPE"PLUMBING"
VOLTAGE"1.2V"
CDS_LIB"mstr_symbols";
"G\NAC"3;
%"GND"
"1","(-3600,975)","0","mstr_symbols","I27";
;
HDL_POWER"GND"
BODY_TYPE"PLUMBING"
SIZE"1B"
BOM_COST"PROC_VRD_VCCIN_CPU0"
ROOM"VDDQ_ABC_PWR_VR"
VOLTAGE"0"
CDS_LIB"mstr_symbols";
"A\NAC"4;
%"PVDDQ_KLM"
"1","(-3600,1800)","0","mstr_symbols","I29";
;
HDL_POWER"PVDDQ_KLM"
BODY_TYPE"PLUMBING"
VOLTAGE"1.2V"
ROOM"VDDQ_KLM_PWR_VR"
BOM_COST"VDDQ_KLM_PWR_VR"
CDS_LIB"mstr_symbols";
"G\NAC"5;
%"PVDDQ_GHJ"
"1","(-7100,1700)","0","mstr_symbols","I3";
;
HDL_POWER"PVDDQ_GHJ"
BODY_TYPE"PLUMBING"
VOLTAGE"1.2V"
CDS_LIB"mstr_symbols";
"G\NAC"6;
%"GND"
"1","(-3600,2075)","0","mstr_symbols","I34";
;
HDL_POWER"GND"
BODY_TYPE"PLUMBING"
VOLTAGE"0"
ROOM"VDDQ_ABC_PWR_VR"
BOM_COST"PROC_VRD_VCCIN_CPU0"
SIZE"1B"
CDS_LIB"mstr_symbols";
"A\NAC"7;
%"PVDDQ_KLM"
"1","(-3600,2900)","0","mstr_symbols","I36";
;
HDL_POWER"PVDDQ_KLM"
BODY_TYPE"PLUMBING"
VOLTAGE"1.2V"
ROOM"VDDQ_KLM_PWR_VR"
BOM_COST"VDDQ_KLM_PWR_VR"
CDS_LIB"mstr_symbols";
"G\NAC"8;
%"GND"
"1","(-3600,3400)","0","mstr_symbols","I38";
;
HDL_POWER"GND"
BODY_TYPE"PLUMBING"
VOLTAGE"0"
ROOM"VDDQ_ABC_PWR_VR"
BOM_COST"PROC_VRD_VCCIN_CPU0"
SIZE"1B"
CDS_LIB"mstr_symbols";
"A\NAC"9;
%"CAP"
"1","(-3600,3925)","0","mstr_discrete","I39";
;
CDS_SEC"1"
$SEC"1"
CDS_LOCATION"C5G115"
ROOM"VDDQ_KLM_PWR_VR"
BOM_COST"MEM_VRD_PVDDQ_CD"
CDS_LIB"mstr_discrete"
SIDE_SKU"1S"
TOLERANCE"20%"
VOLTAGE"4V"
MATERIAL"X5R"
PACK_TYPE"0805"
LOCATION"C5G115"
VALUE"100UF"
PART_NUMBER"602433-112";
"A"
$PN"1"10;
"B"
$PN"2"9;
%"CAP"
"1","(-3200,3925)","0","mstr_discrete","I43";
;
CDS_SEC"1"
$SEC"1"
CDS_LOCATION"C5G116"
BOM_COST"MEM_VRD_PVDDQ_CD"
ROOM"VDDQ_KLM_PWR_VR"
CDS_LIB"mstr_discrete"
SIDE_SKU"1S"
MATERIAL"X5R"
VOLTAGE"4V"
VALUE"100UF"
LOCATION"C5G116"
PACK_TYPE"0805"
TOLERANCE"20%"
PART_NUMBER"602433-112";
"A"
$PN"1"10;
"B"
$PN"2"9;
%"PVDDQ_KLM"
"1","(-3600,4350)","0","mstr_symbols","I51";
;
HDL_POWER"PVDDQ_KLM"
BODY_TYPE"PLUMBING"
VOLTAGE"1.2V"
ROOM"VDDQ_KLM_PWR_VR"
BOM_COST"VDDQ_KLM_PWR_VR"
CDS_LIB"mstr_symbols";
"G\NAC"10;
%"CAP_A"
"1","(-7125,2500)","0","dev_discrete","I53";
;
CDS_SEC"1"
$SEC"1"
CDS_LOCATION"C5G79"
CDS_LIB"dev_discrete"
ROOM"PVDDQ_KLM"
SIDE_SKU"1S"
LOCATION"C5G79"
PACK_TYPE"0603V"
MATERIAL"X6S"
VOLTAGE"4V"
TOLERANCE"20%"
PART_NUMBER"E15431-004"
VALUE"22.0UF";
"B"
$PN"2"11;
"A"
$PN"1"12;
%"CAP_A"
"1","(-4650,2500)","0","dev_discrete","I54";
;
CDS_SEC"1"
$SEC"1"
CDS_LOCATION"C5G87"
CDS_LIB"dev_discrete"
ROOM"PVDDQ_KLM"
SIDE_SKU"1S"
LOCATION"C5G87"
VALUE"22.0UF"
PART_NUMBER"E15431-004"
PACK_TYPE"0603V"
MATERIAL"X6S"
VOLTAGE"4V"
TOLERANCE"20%";
"B"
$PN"2"11;
"A"
$PN"1"12;
%"CAP_A"
"1","(-4950,2500)","0","dev_discrete","I55";
;
CDS_SEC"1"
$SEC"1"
CDS_LOCATION"C5G86"
CDS_LIB"dev_discrete"
ROOM"PVDDQ_KLM"
SIDE_SKU"1S"
LOCATION"C5G86"
PACK_TYPE"0603V"
MATERIAL"X6S"
VOLTAGE"4V"
TOLERANCE"20%"
PART_NUMBER"E15431-004"
VALUE"22.0UF";
"B"
$PN"2"11;
"A"
$PN"1"12;
%"CAP_A"
"1","(-5250,2500)","0","dev_discrete","I56";
;
CDS_SEC"1"
$SEC"1"
CDS_LOCATION"C5G85"
CDS_LIB"dev_discrete"
ROOM"PVDDQ_KLM"
SIDE_SKU"1S"
LOCATION"C5G85"
PACK_TYPE"0603V"
MATERIAL"X6S"
VOLTAGE"4V"
TOLERANCE"20%"
PART_NUMBER"E15431-004"
VALUE"22.0UF";
"B"
$PN"2"11;
"A"
$PN"1"12;
%"CAP_A"
"1","(-5550,2500)","0","dev_discrete","I57";
;
CDS_SEC"1"
$SEC"1"
CDS_LOCATION"C5G84"
CDS_LIB"dev_discrete"
ROOM"PVDDQ_KLM"
SIDE_SKU"1S"
LOCATION"C5G84"
PACK_TYPE"0603V"
MATERIAL"X6S"
VOLTAGE"4V"
TOLERANCE"20%"
PART_NUMBER"E15431-004"
VALUE"22.0UF";
"B"
$PN"2"11;
"A"
$PN"1"12;
%"CAP_A"
"1","(-5850,2500)","0","dev_discrete","I58";
;
CDS_SEC"1"
$SEC"1"
CDS_LOCATION"C5G83"
CDS_LIB"dev_discrete"
ROOM"PVDDQ_KLM"
SIDE_SKU"1S"
TOLERANCE"20%"
VOLTAGE"4V"
VALUE"22.0UF"
LOCATION"C5G83"
PART_NUMBER"E15431-004"
MATERIAL"X6S"
PACK_TYPE"0603V";
"B"
$PN"2"11;
"A"
$PN"1"12;
%"CAP_A"
"1","(-6150,2500)","0","dev_discrete","I59";
;
CDS_SEC"1"
$SEC"1"
CDS_LOCATION"C5G82"
CDS_LIB"dev_discrete"
ROOM"PVDDQ_KLM"
SIDE_SKU"1S"
LOCATION"C5G82"
VALUE"22.0UF"
PART_NUMBER"E15431-004"
TOLERANCE"20%"
VOLTAGE"4V"
MATERIAL"X6S"
PACK_TYPE"0603V";
"B"
$PN"2"11;
"A"
$PN"1"12;
%"GND"
"1","(-7125,2000)","0","mstr_symbols","I6";
;
HDL_POWER"GND"
BODY_TYPE"PLUMBING"
VOLTAGE"0"
ROOM"VDDQ_ABC_PWR_VR"
BOM_COST"PROC_VRD_VCCIN_CPU0"
SIZE"1B"
CDS_LIB"mstr_symbols";
"A\NAC"11;
%"CAP_A"
"1","(-6500,2500)","0","dev_discrete","I60";
;
CDS_SEC"1"
$SEC"1"
CDS_LOCATION"C5G81"
CDS_LIB"dev_discrete"
ROOM"PVDDQ_KLM"
SIDE_SKU"1S"
LOCATION"C5G81"
PACK_TYPE"0603V"
MATERIAL"X6S"
VOLTAGE"4V"
TOLERANCE"20%"
PART_NUMBER"E15431-004"
VALUE"22.0UF";
"B"
$PN"2"11;
"A"
$PN"1"12;
%"CAP_A"
"1","(-6800,2500)","0","dev_discrete","I61";
;
CDS_SEC"1"
$SEC"1"
CDS_LOCATION"C5G80"
CDS_LIB"dev_discrete"
ROOM"PVDDQ_KLM"
SIDE_SKU"1S"
LOCATION"C5G80"
PACK_TYPE"0603V"
MATERIAL"X6S"
VOLTAGE"4V"
TOLERANCE"20%"
PART_NUMBER"E15431-004"
VALUE"22.0UF";
"B"
$PN"2"11;
"A"
$PN"1"12;
%"CAP_A"
"1","(-4650,1375)","0","dev_discrete","I62";
;
CDS_SEC"1"
$SEC"1"
CDS_LOCATION"C5G96"
ROOM"PVDDQ_KLM"
CDS_LIB"dev_discrete"
SIDE_SKU"1S"
PART_NUMBER"E15431-004"
PACK_TYPE"0603V"
VALUE"22.0UF"
TOLERANCE"20%"
VOLTAGE"4V"
MATERIAL"X6S"
LOCATION"C5G96";
"B"
$PN"2"1;
"A"
$PN"1"6;
%"CAP_A"
"1","(-4950,1375)","0","dev_discrete","I63";
;
CDS_SEC"1"
$SEC"1"
CDS_LOCATION"C5G95"
ROOM"PVDDQ_KLM"
CDS_LIB"dev_discrete"
SIDE_SKU"1S"
PART_NUMBER"E15431-004"
TOLERANCE"20%"
MATERIAL"X6S"
PACK_TYPE"0603V"
VOLTAGE"4V"
LOCATION"C5G95"
VALUE"22.0UF";
"B"
$PN"2"1;
"A"
$PN"1"6;
%"CAP_A"
"1","(-5250,1375)","0","dev_discrete","I64";
;
CDS_SEC"1"
$SEC"1"
CDS_LOCATION"C5G94"
ROOM"PVDDQ_KLM"
CDS_LIB"dev_discrete"
SIDE_SKU"1S"
PART_NUMBER"E15431-004"
MATERIAL"X6S"
VOLTAGE"4V"
TOLERANCE"20%"
VALUE"22.0UF"
LOCATION"C5G94"
PACK_TYPE"0603V";
"B"
$PN"2"1;
"A"
$PN"1"6;
%"CAP_A"
"1","(-5550,1375)","0","dev_discrete","I65";
;
CDS_SEC"1"
$SEC"1"
CDS_LOCATION"C5G93"
ROOM"PVDDQ_KLM"
CDS_LIB"dev_discrete"
SIDE_SKU"1S"
PART_NUMBER"E15431-004"
MATERIAL"X6S"
PACK_TYPE"0603V"
VOLTAGE"4V"
TOLERANCE"20%"
VALUE"22.0UF"
LOCATION"C5G93";
"B"
$PN"2"1;
"A"
$PN"1"6;
%"CAP_A"
"1","(-5850,1375)","0","dev_discrete","I66";
;
CDS_SEC"1"
$SEC"1"
CDS_LOCATION"C5G92"
ROOM"PVDDQ_KLM"
CDS_LIB"dev_discrete"
SIDE_SKU"1S"
MATERIAL"X6S"
VALUE"22.0UF"
TOLERANCE"20%"
VOLTAGE"4V"
LOCATION"C5G92"
PACK_TYPE"0603V"
PART_NUMBER"E15431-004";
"B"
$PN"2"1;
"A"
$PN"1"6;
%"CAP_A"
"1","(-6150,1375)","0","dev_discrete","I67";
;
CDS_SEC"1"
$SEC"1"
CDS_LOCATION"C5G91"
CDS_LIB"dev_discrete"
ROOM"PVDDQ_KLM"
SIDE_SKU"1S"
VALUE"22.0UF"
MATERIAL"X6S"
PART_NUMBER"E15431-004"
PACK_TYPE"0603V"
VOLTAGE"4V"
LOCATION"C5G91"
TOLERANCE"20%";
"B"
$PN"2"1;
"A"
$PN"1"6;
%"CAP_A"
"1","(-6450,1375)","0","dev_discrete","I68";
;
CDS_SEC"1"
$SEC"1"
CDS_LOCATION"C5G90"
ROOM"PVDDQ_KLM"
CDS_LIB"dev_discrete"
SIDE_SKU"1S"
LOCATION"C5G90"
VALUE"22.0UF"
VOLTAGE"4V"
TOLERANCE"20%"
MATERIAL"X6S"
PART_NUMBER"E15431-004"
PACK_TYPE"0603V";
"B"
$PN"2"1;
"A"
$PN"1"6;
%"CAP_A"
"1","(-6775,1375)","0","dev_discrete","I69";
;
CDS_SEC"1"
$SEC"1"
CDS_LOCATION"C5G89"
ROOM"PVDDQ_KLM"
CDS_LIB"dev_discrete"
SIDE_SKU"1S"
PACK_TYPE"0603V"
VOLTAGE"4V"
PART_NUMBER"E15431-004"
VALUE"22.0UF"
MATERIAL"X6S"
LOCATION"C5G89"
TOLERANCE"20%";
"B"
$PN"2"1;
"A"
$PN"1"6;
%"CAP_A"
"1","(-7100,1375)","0","dev_discrete","I70";
;
CDS_SEC"1"
$SEC"1"
CDS_LOCATION"C5G88"
ROOM"PVDDQ_KLM"
CDS_LIB"dev_discrete"
SIDE_SKU"1S"
PACK_TYPE"0603V"
VOLTAGE"4V"
VALUE"22.0UF"
PART_NUMBER"E15431-004"
MATERIAL"X6S"
TOLERANCE"20%"
LOCATION"C5G88";
"B"
$PN"2"1;
"A"
$PN"1"6;
%"CAP_A"
"1","(-1750,2575)","0","dev_discrete","I71";
;
CDS_SEC"1"
$SEC"1"
CDS_LOCATION"C5G103"
CDS_LIB"dev_discrete"
ROOM"PVDDQ_KLM"
SIDE_SKU"1S"
VALUE"22.0UF"
PART_NUMBER"E15431-004"
TOLERANCE"20%"
VOLTAGE"4V"
MATERIAL"X6S"
PACK_TYPE"0603V"
LOCATION"C5G103";
"B"
$PN"2"7;
"A"
$PN"1"8;
%"CAP_A"
"1","(-1450,2575)","0","dev_discrete","I72";
;
CDS_SEC"1"
$SEC"1"
CDS_LOCATION"C5G104"
CDS_LIB"dev_discrete"
ROOM"PVDDQ_KLM"
SIDE_SKU"1S"
VALUE"22.0UF"
PART_NUMBER"E15431-004"
TOLERANCE"20%"
VOLTAGE"4V"
MATERIAL"X6S"
PACK_TYPE"0603V"
LOCATION"C5G104";
"B"
$PN"2"7;
"A"
$PN"1"8;
%"CAP_A"
"1","(-1150,2575)","0","dev_discrete","I73";
;
CDS_SEC"1"
$SEC"1"
CDS_LOCATION"C5G105"
CDS_LIB"dev_discrete"
ROOM"PVDDQ_KLM"
SIDE_SKU"1S"
VALUE"22.0UF"
PART_NUMBER"E15431-004"
TOLERANCE"20%"
VOLTAGE"4V"
MATERIAL"X6S"
PACK_TYPE"0603V"
LOCATION"C5G105";
"B"
$PN"2"7;
"A"
$PN"1"8;
%"CAP_A"
"1","(-2050,2575)","0","dev_discrete","I74";
;
CDS_SEC"1"
$SEC"1"
CDS_LOCATION"C5G102"
CDS_LIB"dev_discrete"
ROOM"PVDDQ_KLM"
SIDE_SKU"1S"
VALUE"22.0UF"
PART_NUMBER"E15431-004"
TOLERANCE"20%"
VOLTAGE"4V"
MATERIAL"X6S"
PACK_TYPE"0603V"
LOCATION"C5G102";
"B"
$PN"2"7;
"A"
$PN"1"8;
%"CAP_A"
"1","(-2350,2575)","0","dev_discrete","I75";
;
CDS_SEC"1"
$SEC"1"
CDS_LOCATION"C5G101"
CDS_LIB"dev_discrete"
ROOM"PVDDQ_KLM"
SIDE_SKU"1S"
VALUE"22.0UF"
PACK_TYPE"0603V"
MATERIAL"X6S"
VOLTAGE"4V"
TOLERANCE"20%"
PART_NUMBER"E15431-004"
LOCATION"C5G101";
"B"
$PN"2"7;
"A"
$PN"1"8;
%"CAP_A"
"1","(-2650,2575)","0","dev_discrete","I76";
;
CDS_SEC"1"
$SEC"1"
CDS_LOCATION"C5G100"
CDS_LIB"dev_discrete"
ROOM"PVDDQ_KLM"
SIDE_SKU"1S"
MATERIAL"X6S"
VOLTAGE"4V"
TOLERANCE"20%"
VALUE"22.0UF"
LOCATION"C5G100"
PART_NUMBER"E15431-004"
PACK_TYPE"0603V";
"B"
$PN"2"7;
"A"
$PN"1"8;
%"CAP_A"
"1","(-3000,2575)","0","dev_discrete","I77";
;
CDS_SEC"1"
$SEC"1"
CDS_LOCATION"C5G99"
CDS_LIB"dev_discrete"
ROOM"PVDDQ_KLM"
SIDE_SKU"1S"
VALUE"22.0UF"
PART_NUMBER"E15431-004"
TOLERANCE"20%"
VOLTAGE"4V"
MATERIAL"X6S"
PACK_TYPE"0603V"
LOCATION"C5G99";
"B"
$PN"2"7;
"A"
$PN"1"8;
%"CAP_A"
"1","(-3300,2575)","0","dev_discrete","I78";
;
CDS_SEC"1"
$SEC"1"
CDS_LOCATION"C5G98"
CDS_LIB"dev_discrete"
ROOM"PVDDQ_KLM"
SIDE_SKU"1S"
VALUE"22.0UF"
PART_NUMBER"E15431-004"
TOLERANCE"20%"
VOLTAGE"4V"
MATERIAL"X6S"
PACK_TYPE"0603V"
LOCATION"C5G98";
"B"
$PN"2"7;
"A"
$PN"1"8;
%"CAP_A"
"1","(-3600,2575)","0","dev_discrete","I79";
;
CDS_SEC"1"
$SEC"1"
CDS_LOCATION"C5G97"
CDS_LIB"dev_discrete"
ROOM"PVDDQ_KLM"
SIDE_SKU"1S"
PACK_TYPE"0603V"
MATERIAL"X6S"
VOLTAGE"4V"
TOLERANCE"20%"
PART_NUMBER"E15431-004"
VALUE"22.0UF"
LOCATION"C5G97";
"B"
$PN"2"7;
"A"
$PN"1"8;
%"PVDDQ_GHJ"
"1","(-7125,2825)","0","mstr_symbols","I8";
;
HDL_POWER"PVDDQ_GHJ"
BODY_TYPE"PLUMBING"
VOLTAGE"1.2V"
CDS_LIB"mstr_symbols";
"G\NAC"12;
%"CAP_A"
"1","(-1150,1475)","0","dev_discrete","I80";
;
CDS_SEC"1"
$SEC"1"
CDS_LOCATION"C5G114"
ROOM"PVDDQ_KLM"
CDS_LIB"dev_discrete"
SIDE_SKU"1S"
PACK_TYPE"0603V"
MATERIAL"X6S"
VOLTAGE"4V"
TOLERANCE"20%"
PART_NUMBER"E15431-004"
VALUE"22.0UF"
LOCATION"C5G114";
"B"
$PN"2"4;
"A"
$PN"1"5;
%"CAP_A"
"1","(-1450,1475)","0","dev_discrete","I81";
;
CDS_SEC"1"
$SEC"1"
CDS_LOCATION"C5G113"
ROOM"PVDDQ_KLM"
CDS_LIB"dev_discrete"
SIDE_SKU"1S"
PACK_TYPE"0603V"
MATERIAL"X6S"
VOLTAGE"4V"
TOLERANCE"20%"
PART_NUMBER"E15431-004"
VALUE"22.0UF"
LOCATION"C5G113";
"B"
$PN"2"4;
"A"
$PN"1"5;
%"CAP_A"
"1","(-1750,1475)","0","dev_discrete","I82";
;
CDS_SEC"1"
$SEC"1"
CDS_LOCATION"C5G112"
ROOM"PVDDQ_KLM"
CDS_LIB"dev_discrete"
SIDE_SKU"1S"
PACK_TYPE"0603V"
MATERIAL"X6S"
VOLTAGE"4V"
TOLERANCE"20%"
PART_NUMBER"E15431-004"
VALUE"22.0UF"
LOCATION"C5G112";
"B"
$PN"2"4;
"A"
$PN"1"5;
%"CAP_A"
"1","(-2050,1475)","0","dev_discrete","I83";
;
CDS_SEC"1"
$SEC"1"
CDS_LOCATION"C5G111"
ROOM"PVDDQ_KLM"
CDS_LIB"dev_discrete"
SIDE_SKU"1S"
PACK_TYPE"0603V"
MATERIAL"X6S"
VOLTAGE"4V"
TOLERANCE"20%"
PART_NUMBER"E15431-004"
VALUE"22.0UF"
LOCATION"C5G111";
"B"
$PN"2"4;
"A"
$PN"1"5;
%"CAP_A"
"1","(-2350,1475)","0","dev_discrete","I84";
;
CDS_SEC"1"
$SEC"1"
CDS_LOCATION"C5G110"
ROOM"PVDDQ_KLM"
CDS_LIB"dev_discrete"
SIDE_SKU"1S"
VALUE"22.0UF"
PART_NUMBER"E15431-004"
TOLERANCE"20%"
MATERIAL"X6S"
PACK_TYPE"0603V"
VOLTAGE"4V"
LOCATION"C5G110";
"B"
$PN"2"4;
"A"
$PN"1"5;
%"CAP_A"
"1","(-2650,1475)","0","dev_discrete","I85";
;
CDS_SEC"1"
$SEC"1"
CDS_LOCATION"C5G109"
ROOM"PVDDQ_KLM"
CDS_LIB"dev_discrete"
SIDE_SKU"1S"
TOLERANCE"20%"
MATERIAL"X6S"
VALUE"22.0UF"
VOLTAGE"4V"
LOCATION"C5G109"
PART_NUMBER"E15431-004"
PACK_TYPE"0603V";
"B"
$PN"2"4;
"A"
$PN"1"5;
%"CAP_A"
"1","(-3000,1475)","0","dev_discrete","I86";
;
CDS_SEC"1"
$SEC"1"
CDS_LOCATION"C5G108"
ROOM"PVDDQ_KLM"
CDS_LIB"dev_discrete"
SIDE_SKU"1S"
PACK_TYPE"0603V"
VOLTAGE"4V"
TOLERANCE"20%"
PART_NUMBER"E15431-004"
VALUE"22.0UF"
MATERIAL"X6S"
LOCATION"C5G108";
"B"
$PN"2"4;
"A"
$PN"1"5;
%"CAP_A"
"1","(-3300,1475)","0","dev_discrete","I87";
;
CDS_SEC"1"
$SEC"1"
CDS_LOCATION"C5G107"
ROOM"PVDDQ_KLM"
CDS_LIB"dev_discrete"
SIDE_SKU"1S"
PACK_TYPE"0603V"
VOLTAGE"4V"
PART_NUMBER"E15431-004"
VALUE"22.0UF"
MATERIAL"X6S"
TOLERANCE"20%"
LOCATION"C5G107";
"B"
$PN"2"4;
"A"
$PN"1"5;
%"CAP_A"
"1","(-3600,1475)","0","dev_discrete","I88";
;
CDS_SEC"1"
$SEC"1"
CDS_LOCATION"C5G106"
ROOM"PVDDQ_KLM"
CDS_LIB"dev_discrete"
SIDE_SKU"1S"
PART_NUMBER"E15431-004"
MATERIAL"X6S"
PACK_TYPE"0603V"
TOLERANCE"20%"
VOLTAGE"4V"
VALUE"22.0UF"
LOCATION"C5G106";
"B"
$PN"2"4;
"A"
$PN"1"5;
END.
